# S9S_MB_2U (Grand Teton) — schematic netlist excerpt (pin names and nets, part order shuffled) for the footprints in the layout excerpt that follows; sources: Cadence DE-HDL packaged netlist, KiCad conversion of 03242023_DA0F0TMBIJ0_F0T_Motherboard_J_brd_V01_OCP.brd

J18  SCONN288_ADR50017P087CC  SCONN288_ADR50017-P087CC IO  pkg DDR288S_1-1VXB  page 99
  VIN_BULK0  = P12V_S3_AUX_CPU1_NVDIMM
  RFU0  = TP_CHA_CPU1_DIMM2_FRU_0
  VIN_MGMT  = P3V3_AUX
  HSCL  = I3C_SPD_DDRABCD_CPU1_LVC1_SCL_1
  HSDA  = I3C_SPD_DDRABCD_CPU1_LVC1_SDA
  VSS0  = GND
  DQ0_A  = M_A_CPU1_SA_DQ<0>
  VSS1  = GND
  DQ1_A  = M_A_CPU1_SA_DQ<1>
  VSS2  = GND
  DQS0_A_T  = M_A_CPU1_SA_DQS_DP<0>
  DQS0_A_C  = M_A_CPU1_SA_DQS_DN<0>
  VSS3  = GND
  DQ4_A  = M_A_CPU1_SA_DQ<4>
  VSS4  = GND
  DQ5_A  = M_A_CPU1_SA_DQ<5>
  VSS5  = GND
  DQ8_A  = M_A_CPU1_SA_DQ<8>
  VSS6  = GND
  DQ9_A  = M_A_CPU1_SA_DQ<9>
  VSS7  = GND
  DQS1_A_T  = M_A_CPU1_SA_DQS_DP<1>
  DQS1_A_C  = M_A_CPU1_SA_DQS_DN<1>
  VSS8  = GND
  DQ12_A  = M_A_CPU1_SA_DQ<12>
  VSS9  = GND
  DQ13_A  = M_A_CPU1_SA_DQ<13>
  VSS10  = GND
  DQ16_A  = M_A_CPU1_SA_DQ<16>
  VSS11  = GND
  DQ17_A  = M_A_CPU1_SA_DQ<17>
  VSS12  = GND
  DQS2_A_T  = M_A_CPU1_SA_DQS_DP<2>
  DQS2_A_C  = M_A_CPU1_SA_DQS_DN<2>
  VSS13  = GND
  DQ20_A  = M_A_CPU1_SA_DQ<20>
  VSS14  = GND
  DQ21_A  = M_A_CPU1_SA_DQ<21>
  VSS15  = GND
  DQ24_A  = M_A_CPU1_SA_DQ<24>
  VSS16  = GND
  DQ25_A  = M_A_CPU1_SA_DQ<25>
  VSS17  = GND
  DQS3_A_T  = M_A_CPU1_SA_DQS_DP<3>
  DQS3_A_C  = M_A_CPU1_SA_DQS_DN<3>
  VSS18  = GND
  DQ28_A  = M_A_CPU1_SA_DQ<28>
  VSS19  = GND
  DQ29_A  = M_A_CPU1_SA_DQ<29>
  VSS20  = GND
  CB0_A  = M_A_CPU1_SA_CB<0>
  VSS21  = GND
  CB1_A  = M_A_CPU1_SA_CB<1>
  VSS22  = GND
  DQS4_A_T  = M_A_CPU1_SA_DQS_DP<4>
  DQS4_A_C  = M_A_CPU1_SA_DQS_DN<4>
  VSS23  = GND
  CB4_A  = M_A_CPU1_SA_CB<4>
  VSS24  = GND
  CB5_A  = M_A_CPU1_SA_CB<5>
  VSS25  = GND
  ALERT_N  = M_A_CPU1_ALERT_N
  VSS26  = GND
  CS0_A_N  = M_A_CPU1_SA_CS_N<2>
  VSS27  = GND
  CA0_A  = M_A_CPU1_SA_CA<0>
  VSS28  = GND
  CA2_A  = M_A_CPU1_SA_CA<2>
  VSS29  = GND
  CA4_A  = M_A_CPU1_SA_CA<4>
  VSS30  = GND
  CA6_A  = M_A_CPU1_SA_CA<6>
  VSS31  = GND
  PAR_A  = M_A_CPU1_SA_PAR
  VSS32  = GND
  CA0_B  = M_A_CPU1_SB_CA<0>
  VSS33  = GND
  CA2_B  = M_A_CPU1_SB_CA<2>
  VSS34  = GND
  CA4_B  = M_A_CPU1_SB_CA<4>
  VSS35  = GND
  CA6_B  = M_A_CPU1_SB_CA<6>
  VSS36  = GND
  CS0_B_N  = M_A_CPU1_SB_CS_N<2>
  VSS37  = GND
  \lbd||rsp_a_n\  = M_A_CPU1_SA_RSP<1>
  \lbs||rsp_b_n\  = M_A_CPU1_SB_RSP<1>
  VSS38  = GND
  CB4_B  = M_A_CPU1_SB_CB<4>
  VSS39  = GND
  CB5_B  = M_A_CPU1_SB_CB<5>
  VSS40  = GND
  \dqs9_b_t||tdqs9_b_t||dbi4_b_n\  = M_A_CPU1_SB_DQS_DP<9>
  \dqs9_b_c||tdqs9_b_c\  = M_A_CPU1_SB_DQS_DN<9>
  VSS41  = GND
  CB0_B  = M_A_CPU1_SB_CB<0>
  VSS42  = GND
  CB1_B  = M_A_CPU1_SB_CB<1>
  VSS43  = GND
  DQ0_B  = M_A_CPU1_SB_DQ<0>
  VSS44  = GND
  DQ1_B  = M_A_CPU1_SB_DQ<1>
  VSS45  = GND
  DQS0_B_T  = M_A_CPU1_SB_DQS_DP<0>
  DQS0_B_C  = M_A_CPU1_SB_DQS_DN<0>
  VSS46  = GND
  DQ4_B  = M_A_CPU1_SB_DQ<4>
  VSS47  = GND
  DQ5_B  = M_A_CPU1_SB_DQ<5>
  VSS48  = GND
  DQ8_B  = M_A_CPU1_SB_DQ<8>
  VSS49  = GND
  DQ9_B  = M_A_CPU1_SB_DQ<9>
  VSS50  = GND
  DQS1_B_T  = M_A_CPU1_SB_DQS_DP<1>
  DQS1_B_C  = M_A_CPU1_SB_DQS_DN<1>
  VSS51  = GND
  DQ12_B  = M_A_CPU1_SB_DQ<12>
  VSS52  = GND
  DQ13_B  = M_A_CPU1_SB_DQ<13>
  VSS53  = GND
  DQ16_B  = M_A_CPU1_SB_DQ<16>
  VSS54  = GND
  DQ17_B  = M_A_CPU1_SB_DQ<17>
  VSS55  = GND
  DQS2_B_T  = M_A_CPU1_SB_DQS_DP<2>
  DQS2_B_C  = M_A_CPU1_SB_DQS_DN<2>
  VSS56  = GND
  DQ20_B  = M_A_CPU1_SB_DQ<20>
  VSS57  = GND
  DQ21_B  = M_A_CPU1_SB_DQ<21>
  VSS58  = GND
  DQ24_B  = M_A_CPU1_SB_DQ<24>
  VSS59  = GND
  DQ25_B  = M_A_CPU1_SB_DQ<25>
  VSS60  = GND
  DQS3_B_T  = M_A_CPU1_SB_DQS_DP<3>
  DQS3_B_C  = M_A_CPU1_SB_DQS_DN<3>
  VSS61  = GND
  DQ28_B  = M_A_CPU1_SB_DQ<28>
  VSS62  = GND
  DQ29_B  = M_A_CPU1_SB_DQ<29>
  VSS63  = GND
  RFU1  = TP_CHA_CPU1_DIMM2_FRU_1
  VIN_BULK1  = P12V_S3_AUX_CPU1_NVDIMM
  VIN_BULK2  = P12V_S3_AUX_CPU1_NVDIMM
  \pwr_good||fail_n\  = PWRGD_CHA_CPU1_DIMM2
  HSA  = PD_CHA_CPU1_DIMM2_SAA
  RFU2  = TP_CHA_CPU1_DIMM2_FRU_2
  RFU3  = TP_CHA_CPU1_DIMM2_FRU_3
  VSS64  = GND
  DQ2_A  = M_A_CPU1_SA_DQ<2>
  VSS65  = GND
  DQ3_A  = M_A_CPU1_SA_DQ<3>
  VSS66  = GND
  \dqs5_a_c||tdqs5_a_c||dqs5_a_t||tdqs5_a_t\  = M_A_CPU1_SA_DQS_DN<5>
  \dqs5_a_t||tdqs5_a_t\  = M_A_CPU1_SA_DQS_DP<5>
  VSS67  = GND
  DQ6_A  = M_A_CPU1_SA_DQ<6>
  VSS68  = GND
  DQ7_A  = M_A_CPU1_SA_DQ<7>
  VSS69  = GND
  DQ10_A  = M_A_CPU1_SA_DQ<10>
  VSS70  = GND
  DQ11_A  = M_A_CPU1_SA_DQ<11>
  VSS71  = GND
  \dqs6_a_c||tdqs6_a_c||dqs6_a_t||tdqs6_a_t\  = M_A_CPU1_SA_DQS_DN<6>
  \dqs6_a_t||tdqs6_a_t\  = M_A_CPU1_SA_DQS_DP<6>
  VSS72  = GND
  DQ14_A  = M_A_CPU1_SA_DQ<14>
  VSS73  = GND
  DQ15_A  = M_A_CPU1_SA_DQ<15>
  VSS74  = GND
  DQ18_A  = M_A_CPU1_SA_DQ<18>
  VSS75  = GND
  DQ19_A  = M_A_CPU1_SA_DQ<19>
  VSS76  = GND
  \dqs7_a_c||tdqs7_a_c\  = M_A_CPU1_SA_DQS_DN<7>
  \dqs7_a_t||tdqs7_a_t\  = M_A_CPU1_SA_DQS_DP<7>
  VSS77  = GND
  DQ22_A  = M_A_CPU1_SA_DQ<22>
  VSS78  = GND
  DQ23_A  = M_A_CPU1_SA_DQ<23>
  VSS79  = GND
  DQ26_A  = M_A_CPU1_SA_DQ<26>
  VSS80  = GND
  DQ27_A  = M_A_CPU1_SA_DQ<27>
  VSS81  = GND
  \dqs8_a_c||tdqs8_a_c\  = M_A_CPU1_SA_DQS_DN<8>
  \dqs8_a_t||tdqs8_a_t\  = M_A_CPU1_SA_DQS_DP<8>
  VSS82  = GND
  DQ30_A  = M_A_CPU1_SA_DQ<30>
  VSS83  = GND
  DQ31_A  = M_A_CPU1_SA_DQ<31>
  VSS84  = GND
  CB2_A  = M_A_CPU1_SA_CB<2>
  VSS85  = GND
  CB3_A  = M_A_CPU1_SA_CB<3>
  VSS86  = GND
  \dqs9_a_c||tdqs9_a_c\  = M_A_CPU1_SA_DQS_DN<9>
  \dqs9_a_t||tdqs9_a_t\  = M_A_CPU1_SA_DQS_DP<9>
  VSS87  = GND
  CB6_A  = M_A_CPU1_SA_CB<6>
  VSS88  = GND
  CB7_A  = M_A_CPU1_SA_CB<7>
  VSS89  = GND
  RESET_N  = RST_M_AB_CPU1_FPGA_N
  VSS90  = GND
  CS1_A_N  = M_A_CPU1_SA_CS_N<3>
  VSS91  = GND
  CA1_A  = M_A_CPU1_SA_CA<1>
  VSS92  = GND
  CA3_A  = M_A_CPU1_SA_CA<3>
  VSS93  = GND
  CA5_A  = M_A_CPU1_SA_CA<5>
  VSS94  = GND
  CK_T  = M_A_CPU1_CLK_DP<1>
  CK_C  = M_A_CPU1_CLK_DN<1>
  VSS95  = GND
  RFU4  = TP_CHA_CPU1_DIMM2_FRU_4
  CA1_B  = M_A_CPU1_SB_CA<1>
  VSS96  = GND
  CA3_B  = M_A_CPU1_SB_CA<3>
  VSS97  = GND
  CA5_B  = M_A_CPU1_SB_CA<5>
  VSS98  = GND
  PAR_B  = M_A_CPU1_SB_PAR
  VSS99  = GND
  CS1_B_N  = M_A_CPU1_SB_CS_N<3>
  VSS100  = GND
  RFU5  = TP_CHA_CPU1_DIMM2_FRU_5
  RFU6  = TP_CHA_CPU1_DIMM2_FRU_6
  VSS101  = GND
  CB6_B  = M_A_CPU1_SB_CB<6>
  VSS102  = GND
  CB7_B  = M_A_CPU1_SB_CB<7>
  VSS103  = GND
  DQS4_B_C  = M_A_CPU1_SB_DQS_DN<4>
  DQS4_B_T  = M_A_CPU1_SB_DQS_DP<4>
  VSS104  = GND
  CB2_B  = M_A_CPU1_SB_CB<2>
  VSS105  = GND
  CB3_B  = M_A_CPU1_SB_CB<3>
  VSS106  = GND
  DQ2_B  = M_A_CPU1_SB_DQ<2>
  VSS107  = GND
  DQ3_B  = M_A_CPU1_SB_DQ<3>
  VSS108  = GND
  \dqs5_b_c||tdqs5_b_c\  = M_A_CPU1_SB_DQS_DN<5>
  \dqs5_b_t||tdqs5_b_t\  = M_A_CPU1_SB_DQS_DP<5>
  VSS109  = GND
  DQ6_B  = M_A_CPU1_SB_DQ<6>
  VSS110  = GND
  DQ7_B  = M_A_CPU1_SB_DQ<7>
  VSS111  = GND
  DQ10_B  = M_A_CPU1_SB_DQ<10>
  VSS112  = GND
  DQ11_B  = M_A_CPU1_SB_DQ<11>
  VSS113  = GND
  \dqs6_b_c||tdqs6_b_c\  = M_A_CPU1_SB_DQS_DN<6>
  \dqs6_b_t||tdqs6_b_t\  = M_A_CPU1_SB_DQS_DP<6>
  VSS114  = GND
  DQ14_B  = M_A_CPU1_SB_DQ<14>
  VSS115  = GND
  DQ15_B  = M_A_CPU1_SB_DQ<15>
  VSS116  = GND
  DQ18_B  = M_A_CPU1_SB_DQ<18>
  VSS117  = GND
  DQ19_B  = M_A_CPU1_SB_DQ<19>
  VSS118  = GND
  \dqs7_b_c||tdqs7_b_c\  = M_A_CPU1_SB_DQS_DN<7>
  \dqs7_b_t||tdqs7_b_t\  = M_A_CPU1_SB_DQS_DP<7>
  VSS119  = GND
  DQ22_B  = M_A_CPU1_SB_DQ<22>
  VSS120  = GND
  DQ23_B  = M_A_CPU1_SB_DQ<23>
  VSS121  = GND
  DQ26_B  = M_A_CPU1_SB_DQ<26>
  VSS122  = GND
  DQ27_B  = M_A_CPU1_SB_DQ<27>
  VSS123  = GND
  \dqs8_b_c||tdqs8_b_c\  = M_A_CPU1_SB_DQS_DN<8>
  \dqs8_b_t||tdqs8_b_t\  = M_A_CPU1_SB_DQS_DP<8>
  VSS124  = GND
  DQ30_B  = M_A_CPU1_SB_DQ<30>
  VSS125  = GND
  DQ31_B  = M_A_CPU1_SB_DQ<31>
  VSS126  = GND
  G1  = GND
  G2  = GND
  G3  = GND

(kicad_pcb
	(version 20260206)
	(generator "pcbnew")
	(generator_version "10.0")
	(general
		(thickness 1.6)
		(legacy_teardrops no)
	)
	(paper "A4")
	(title_block
		(title "03242023_DA0F0TMBIJ0_F0T_Motherboard_J_brd_V01_OCP.brd")
		(comment 1 "Grand Teton / footprint 3819 of 6105 (J18), pads 1-45 of 291")
	)
	(layers
		(0 "F.Cu" signal "TOP")
		(4 "In1.Cu" signal "GND")
		(6 "In2.Cu" signal "IN1")
		(8 "In3.Cu" signal "GND1")
		(10 "In4.Cu" signal "IN2")
		(12 "In5.Cu" signal "GND2")
		(14 "In6.Cu" signal "IN3")
		(16 "In7.Cu" signal "GND3")
		(18 "In8.Cu" signal "VCC")
		(20 "In9.Cu" signal "VCC1")
		(22 "In10.Cu" signal "GND4")
		(24 "In11.Cu" signal "IN4")
		(26 "In12.Cu" signal "GND5")
		(28 "In13.Cu" signal "IN5")
		(30 "In14.Cu" signal "GND6")
		(32 "In15.Cu" signal "IN6")
		(34 "In16.Cu" signal "GND7")
		(2 "B.Cu" signal "BOTTOM")
		(9 "F.Adhes" user "F.Adhesive")
		(11 "B.Adhes" user "B.Adhesive")
		(13 "F.Paste" user "Package Geometry/Pastemask Top")
		(15 "B.Paste" user "Package Geometry/Pastemask Bottom")
		(5 "F.SilkS" user "Ref Des/Silkscreen Top")
		(7 "B.SilkS" user "Ref Des/Silkscreen Bottom")
		(1 "F.Mask" user "Board Geometry/Soldermask Top")
		(3 "B.Mask" user "Board Geometry/Soldermask Bottom")
		(17 "Dwgs.User" user "User.Drawings")
		(19 "Cmts.User" user "User.Comments")
		(21 "Eco1.User" user "User.Eco1")
		(23 "Eco2.User" user "User.Eco2")
		(25 "Edge.Cuts" user "Board Geometry/Outline")
		(27 "Margin" user)
		(31 "F.CrtYd" user "Package Geometry/Place Bound Top")
		(29 "B.CrtYd" user "Package Geometry/Place Bound Bottom")
		(35 "F.Fab" user "Ref Des/Assembly Top")
		(33 "B.Fab" user "Ref Des/Assembly Bottom")
	)
	(footprint ""
		(layer "F.Cu")
		(at 62.99708 -258.091686)
		(property "Reference" "J18"
			(at -1.547622 -81.836514 0)
			(unlocked yes)
			(layer "F.SilkS")
			(effects
				(font
					(size 0.7874 0.5842)
					(thickness 0.1524)
				)
				(justify left)
			)
		)
		(property "Value" ""
			(at 0 0 0)
			(layer "F.Fab")
			(effects
				(font
					(size 1.27 1.27)
				)
			)
		)
		(duplicate_pad_numbers_are_jumpers no)
		(pad "1" smd rect
			(at -2.050034 -63.324994 270)
			(size 0.519938 1.4986)
			(layers "F.Cu" "F.Mask" "F.Paste")
			(net "P12V_S3_AUX_CPU1_NVDIMM")
		)
		(pad "2" smd rect
			(at -2.050034 -62.47511 270)
			(size 0.519938 1.4986)
			(layers "F.Cu" "F.Mask" "F.Paste")
			(net "TP_CHA_CPU1_DIMM2_FRU_0")
		)
		(pad "3" smd rect
			(at -2.050034 -61.624972 270)
			(size 0.519938 1.4986)
			(layers "F.Cu" "F.Mask" "F.Paste")
			(net "P3V3_AUX")
		)
		(pad "4" smd rect
			(at -2.050034 -60.775088 270)
			(size 0.519938 1.4986)
			(layers "F.Cu" "F.Mask" "F.Paste")
			(net "I3C_SPD_DDRABCD_CPU1_LVC1_SCL_1")
		)
		(pad "5" smd rect
			(at -2.050034 -59.92495 270)
			(size 0.519938 1.4986)
			(layers "F.Cu" "F.Mask" "F.Paste")
			(net "I3C_SPD_DDRABCD_CPU1_LVC1_SDA")
		)
		(pad "6" smd rect
			(at -2.050034 -59.075066 270)
			(size 0.519938 1.4986)
			(layers "F.Cu" "F.Mask" "F.Paste")
			(net "GND")
		)
		(pad "7" smd rect
			(at -2.050034 -58.224928 270)
			(size 0.519938 1.4986)
			(layers "F.Cu" "F.Mask" "F.Paste")
			(net "M_A_CPU1_SA_DQ<0>")
		)
		(pad "8" smd rect
			(at -2.050034 -57.375044 270)
			(size 0.519938 1.4986)
			(layers "F.Cu" "F.Mask" "F.Paste")
			(net "GND")
		)
		(pad "9" smd rect
			(at -2.050034 -56.524906 270)
			(size 0.519938 1.4986)
			(layers "F.Cu" "F.Mask" "F.Paste")
			(net "M_A_CPU1_SA_DQ<1>")
		)
		(pad "10" smd rect
			(at -2.050034 -55.675022 270)
			(size 0.519938 1.4986)
			(layers "F.Cu" "F.Mask" "F.Paste")
			(net "GND")
		)
		(pad "11" smd rect
			(at -2.050034 -54.824884 270)
			(size 0.519938 1.4986)
			(layers "F.Cu" "F.Mask" "F.Paste")
			(net "M_A_CPU1_SA_DQS_DP<0>")
		)
		(pad "12" smd rect
			(at -2.050034 -53.975 270)
			(size 0.519938 1.4986)
			(layers "F.Cu" "F.Mask" "F.Paste")
			(net "M_A_CPU1_SA_DQS_DN<0>")
		)
		(pad "13" smd rect
			(at -2.050034 -53.125116 270)
			(size 0.519938 1.4986)
			(layers "F.Cu" "F.Mask" "F.Paste")
			(net "GND")
		)
		(pad "14" smd rect
			(at -2.050034 -52.274978 270)
			(size 0.519938 1.4986)
			(layers "F.Cu" "F.Mask" "F.Paste")
			(net "M_A_CPU1_SA_DQ<4>")
		)
		(pad "15" smd rect
			(at -2.050034 -51.425094 270)
			(size 0.519938 1.4986)
			(layers "F.Cu" "F.Mask" "F.Paste")
			(net "GND")
		)
		(pad "16" smd rect
			(at -2.050034 -50.574956 270)
			(size 0.519938 1.4986)
			(layers "F.Cu" "F.Mask" "F.Paste")
			(net "M_A_CPU1_SA_DQ<5>")
		)
		(pad "17" smd rect
			(at -2.050034 -49.725072 270)
			(size 0.519938 1.4986)
			(layers "F.Cu" "F.Mask" "F.Paste")
			(net "GND")
		)
		(pad "18" smd rect
			(at -2.050034 -48.874934 270)
			(size 0.519938 1.4986)
			(layers "F.Cu" "F.Mask" "F.Paste")
			(net "M_A_CPU1_SA_DQ<8>")
		)
		(pad "19" smd rect
			(at -2.050034 -48.02505 270)
			(size 0.519938 1.4986)
			(layers "F.Cu" "F.Mask" "F.Paste")
			(net "GND")
		)
		(pad "20" smd rect
			(at -2.050034 -47.174912 270)
			(size 0.519938 1.4986)
			(layers "F.Cu" "F.Mask" "F.Paste")
			(net "M_A_CPU1_SA_DQ<9>")
		)
		(pad "21" smd rect
			(at -2.050034 -46.325028 270)
			(size 0.519938 1.4986)
			(layers "F.Cu" "F.Mask" "F.Paste")
			(net "GND")
		)
		(pad "22" smd rect
			(at -2.050034 -45.47489 270)
			(size 0.519938 1.4986)
			(layers "F.Cu" "F.Mask" "F.Paste")
			(net "M_A_CPU1_SA_DQS_DP<1>")
		)
		(pad "23" smd rect
			(at -2.050034 -44.625006 270)
			(size 0.519938 1.4986)
			(layers "F.Cu" "F.Mask" "F.Paste")
			(net "M_A_CPU1_SA_DQS_DN<1>")
		)
		(pad "24" smd rect
			(at -2.050034 -43.775122 270)
			(size 0.519938 1.4986)
			(layers "F.Cu" "F.Mask" "F.Paste")
			(net "GND")
		)
		(pad "25" smd rect
			(at -2.050034 -42.924984 270)
			(size 0.519938 1.4986)
			(layers "F.Cu" "F.Mask" "F.Paste")
			(net "M_A_CPU1_SA_DQ<12>")
		)
		(pad "26" smd rect
			(at -2.050034 -42.0751 270)
			(size 0.519938 1.4986)
			(layers "F.Cu" "F.Mask" "F.Paste")
			(net "GND")
		)
		(pad "27" smd rect
			(at -2.050034 -41.224962 270)
			(size 0.519938 1.4986)
			(layers "F.Cu" "F.Mask" "F.Paste")
			(net "M_A_CPU1_SA_DQ<13>")
		)
		(pad "28" smd rect
			(at -2.050034 -40.375078 270)
			(size 0.519938 1.4986)
			(layers "F.Cu" "F.Mask" "F.Paste")
			(net "GND")
		)
		(pad "29" smd rect
			(at -2.050034 -39.52494 270)
			(size 0.519938 1.4986)
			(layers "F.Cu" "F.Mask" "F.Paste")
			(net "M_A_CPU1_SA_DQ<16>")
		)
		(pad "30" smd rect
			(at -2.050034 -38.675056 270)
			(size 0.519938 1.4986)
			(layers "F.Cu" "F.Mask" "F.Paste")
			(net "GND")
		)
		(pad "31" smd rect
			(at -2.050034 -37.824918 270)
			(size 0.519938 1.4986)
			(layers "F.Cu" "F.Mask" "F.Paste")
			(net "M_A_CPU1_SA_DQ<17>")
		)
		(pad "32" smd rect
			(at -2.050034 -36.975034 270)
			(size 0.519938 1.4986)
			(layers "F.Cu" "F.Mask" "F.Paste")
			(net "GND")
		)
		(pad "33" smd rect
			(at -2.050034 -36.124896 270)
			(size 0.519938 1.4986)
			(layers "F.Cu" "F.Mask" "F.Paste")
			(net "M_A_CPU1_SA_DQS_DP<2>")
		)
		(pad "34" smd rect
			(at -2.050034 -35.275012 270)
			(size 0.519938 1.4986)
			(layers "F.Cu" "F.Mask" "F.Paste")
			(net "M_A_CPU1_SA_DQS_DN<2>")
		)
		(pad "35" smd rect
			(at -2.050034 -34.425128 270)
			(size 0.519938 1.4986)
			(layers "F.Cu" "F.Mask" "F.Paste")
			(net "GND")
		)
		(pad "36" smd rect
			(at -2.050034 -33.57499 270)
			(size 0.519938 1.4986)
			(layers "F.Cu" "F.Mask" "F.Paste")
			(net "M_A_CPU1_SA_DQ<20>")
		)
		(pad "37" smd rect
			(at -2.050034 -32.725106 270)
			(size 0.519938 1.4986)
			(layers "F.Cu" "F.Mask" "F.Paste")
			(net "GND")
		)
		(pad "38" smd rect
			(at -2.050034 -31.874968 270)
			(size 0.519938 1.4986)
			(layers "F.Cu" "F.Mask" "F.Paste")
			(net "M_A_CPU1_SA_DQ<21>")
		)
		(pad "39" smd rect
			(at -2.050034 -31.025084 270)
			(size 0.519938 1.4986)
			(layers "F.Cu" "F.Mask" "F.Paste")
			(net "GND")
		)
		(pad "40" smd rect
			(at -2.050034 -30.174946 270)
			(size 0.519938 1.4986)
			(layers "F.Cu" "F.Mask" "F.Paste")
			(net "M_A_CPU1_SA_DQ<24>")
		)
		(pad "41" smd rect
			(at -2.050034 -29.325062 270)
			(size 0.519938 1.4986)
			(layers "F.Cu" "F.Mask" "F.Paste")
			(net "GND")
		)
		(pad "42" smd rect
			(at -2.050034 -28.474924 270)
			(size 0.519938 1.4986)
			(layers "F.Cu" "F.Mask" "F.Paste")
			(net "M_A_CPU1_SA_DQ<25>")
		)
		(pad "43" smd rect
			(at -2.050034 -27.62504 270)
			(size 0.519938 1.4986)
			(layers "F.Cu" "F.Mask" "F.Paste")
			(net "GND")
		)
		(pad "44" smd rect
			(at -2.050034 -26.774902 270)
			(size 0.519938 1.4986)
			(layers "F.Cu" "F.Mask" "F.Paste")
			(net "M_A_CPU1_SA_DQS_DP<3>")
		)
		(pad "45" smd rect
			(at -2.050034 -25.925018 270)
			(size 0.519938 1.4986)
			(layers "F.Cu" "F.Mask" "F.Paste")
			(net "M_A_CPU1_SA_DQS_DN<3>")
		)
	)
)
